# S9S_MB_2U (Grand Teton) — schematic parts with pin connectivity, parts 3092–3105 of 6093; source: Cadence DE-HDL packaged netlist (pstxprt.dat, pstxnet.dat, pstchip.dat)

PU6_P0_8  ISL99390FRZTR5935  ISL99390FRZ-TR5935 IC  pkg QFN21_6X5XB  page 270
  1  VOS  IN  = PVCCIN_CPU0_VOS8
  2  AGND  POWER  = GND
  3  VCC  POWER  = PVCCIN_CPU0_VDD8
  4  PVCC  POWER  = PVCCIN_CPU0_PVCC
  5  PGND1  POWER  = GND
  6  GL1  OUT  = NC
  7_9-20_24  PGND2  POWER  = GND
  10_19  SW  OUT  = SW_PVCCIN_CPU0_SW8
  25_29  VIN1  IN  = SW_P12V_PVCCIN_CPU0_FLT
  30  VIN2  IN  = SW_P12V_PVCCIN_CPU0_FLT
  31  DNC  TRI  = NC
  32  PHASE  POWER  = SW_PVCCIN_CPU0_BOOTR8
  33  BOOT  POWER  = SW_PVCCIN_CPU0_BOOT8
  34  PWM  IN  = PVCCIN_CPU0_PWM8
  35  EN  IN  = PVCCIN_CPU0_VDD8
  36  TOUT_FLT  OUT  = PVCCIN_CPU0_ATSEN
  37  LSET  OUT  = PVCCIN_CPU0_LSET8
  38  IOUT  OUT  = PVCCIN_CPU0_IMON8
  39  REFIN  IN  = PVCCIN_CPU0_VREF
  40  PGND3  POWER  = GND
  41  GL2  OUT  = NC

PU7_P0_7  ISL99390FRZTR5935  ISL99390FRZ-TR5935 IC  pkg QFN21_6X5XB  page 270
  1  VOS  IN  = PVCCIN_CPU0_VOS7
  2  AGND  POWER  = GND
  3  VCC  POWER  = PVCCIN_CPU0_VDD7
  4  PVCC  POWER  = PVCCIN_CPU0_PVCC
  5  PGND1  POWER  = GND
  6  GL1  OUT  = NC
  7_9-20_24  PGND2  POWER  = GND
  10_19  SW  OUT  = SW_PVCCIN_CPU0_SW7
  25_29  VIN1  IN  = SW_P12V_PVCCIN_CPU0_FLT
  30  VIN2  IN  = SW_P12V_PVCCIN_CPU0_FLT
  31  DNC  TRI  = NC
  32  PHASE  POWER  = SW_PVCCIN_CPU0_BOOTR7
  33  BOOT  POWER  = SW_PVCCIN_CPU0_BOOT7
  34  PWM  IN  = PVCCIN_CPU0_PWM7
  35  EN  IN  = PVCCIN_CPU0_VDD7
  36  TOUT_FLT  OUT  = PVCCIN_CPU0_ATSEN
  37  LSET  OUT  = PVCCIN_CPU0_LSET7
  38  IOUT  OUT  = PVCCIN_CPU0_IMON7
  39  REFIN  IN  = PVCCIN_CPU0_VREF
  40  PGND3  POWER  = GND
  41  GL2  OUT  = NC

PU8_P0_6  ISL99390FRZTR5935  ISL99390FRZ-TR5935 IC  pkg QFN21_6X5XB  page 269
  1  VOS  IN  = PVCCIN_CPU0_VOS6
  2  AGND  POWER  = GND
  3  VCC  POWER  = PVCCIN_CPU0_VDD6
  4  PVCC  POWER  = PVCCIN_CPU0_PVCC
  5  PGND1  POWER  = GND
  6  GL1  OUT  = NC
  7_9-20_24  PGND2  POWER  = GND
  10_19  SW  OUT  = SW_PVCCIN_CPU0_SW6
  25_29  VIN1  IN  = SW_P12V_PVCCIN_CPU0_FLT
  30  VIN2  IN  = SW_P12V_PVCCIN_CPU0_FLT
  31  DNC  TRI  = NC
  32  PHASE  POWER  = SW_PVCCIN_CPU0_BOOTR6
  33  BOOT  POWER  = SW_PVCCIN_CPU0_BOOT6
  34  PWM  IN  = PVCCIN_CPU0_PWM6
  35  EN  IN  = PVCCIN_CPU0_VDD6
  36  TOUT_FLT  OUT  = PVCCIN_CPU0_ATSEN
  37  LSET  OUT  = PVCCIN_CPU0_LSET6
  38  IOUT  OUT  = PVCCIN_CPU0_IMON6
  39  REFIN  IN  = PVCCIN_CPU0_VREF
  40  PGND3  POWER  = GND
  41  GL2  OUT  = NC

PU9  IR3889MTRPBF  IC  pkg QFN22_6X5  page 259
  1  ILIM  IN  = P3V3_AUX_ILIM
  2  PGOOD  OUT  = PWRGD_P3V3_AUX
  3  VIN  POWER  = P12V_AUX
  4  \vcc||ldo\  POWER  = P3V3_AUX_VCC
  5  VDRV  POWER  = P3V3_AUX_VDRV
  6  GATEL1  IN  = NC_PU9_3
  7_10-19  PGND  POWER  = GND
  11_18  SW  POWER  = SW_P3V3_AUX_SW
  20_24  PVIN  POWER  = SW_P3V3_AUX_FLT
  25  PHASE  OUT  = SW_P3V3_AUX_BOOTR
  26  BOOT  IN  = SW_P3V3_AUX_BOOT
  27  EN  IN  = P3V3_AUX_EN
  28  NC1  TRI  = P3V3_AUX_VOS
  29  \ss||latch\  IN  = P3V3_AUX_SS
  30  FB  IN  = P3V3_AUX_FB
  31  VSENM  IN  = GND
  32  AGND  POWER  = GND
  33  NC2  TRI  = NC_PU9_1
  34  NC3  TRI  = NC_PU9_2
  35  NC4  TRI  = NC_HICCUP
  36  \ton||mode\  IN  = P3V3_AUX_MODE
  37  GATEL2  IN  = NC_PU9_4

PU9_P0_5  ISL99390FRZTR5935  ISL99390FRZ-TR5935 IC  pkg QFN21_6X5XB  page 269
  1  VOS  IN  = PVCCIN_CPU0_VOS5
  2  AGND  POWER  = GND
  3  VCC  POWER  = PVCCIN_CPU0_VDD5
  4  PVCC  POWER  = PVCCIN_CPU0_PVCC
  5  PGND1  POWER  = GND
  6  GL1  OUT  = NC
  7_9-20_24  PGND2  POWER  = GND
  10_19  SW  OUT  = SW_PVCCIN_CPU0_SW5
  25_29  VIN1  IN  = SW_P12V_PVCCIN_CPU0_FLT
  30  VIN2  IN  = SW_P12V_PVCCIN_CPU0_FLT
  31  DNC  TRI  = NC
  32  PHASE  POWER  = SW_PVCCIN_CPU0_BOOTR5
  33  BOOT  POWER  = SW_PVCCIN_CPU0_BOOT5
  34  PWM  IN  = PVCCIN_CPU0_PWM5
  35  EN  IN  = PVCCIN_CPU0_VDD5
  36  TOUT_FLT  OUT  = PVCCIN_CPU0_ATSEN
  37  LSET  OUT  = PVCCIN_CPU0_LSET5
  38  IOUT  OUT  = PVCCIN_CPU0_IMON5
  39  REFIN  IN  = PVCCIN_CPU0_VREF
  40  PGND3  POWER  = GND
  41  GL2  OUT  = NC

PU10_P0_4  ISL99390FRZTR5935  ISL99390FRZ-TR5935 IC  pkg QFN21_6X5XB  page 268
  1  VOS  IN  = PVCCIN_CPU0_VOS4
  2  AGND  POWER  = GND
  3  VCC  POWER  = PVCCIN_CPU0_VDD4
  4  PVCC  POWER  = PVCCIN_CPU0_PVCC
  5  PGND1  POWER  = GND
  6  GL1  OUT  = NC
  7_9-20_24  PGND2  POWER  = GND
  10_19  SW  OUT  = SW_PVCCIN_CPU0_SW4
  25_29  VIN1  IN  = SW_P12V_PVCCIN_CPU0_FLT
  30  VIN2  IN  = SW_P12V_PVCCIN_CPU0_FLT
  31  DNC  TRI  = NC
  32  PHASE  POWER  = SW_PVCCIN_CPU0_BOOTR4
  33  BOOT  POWER  = SW_PVCCIN_CPU0_BOOT4
  34  PWM  IN  = PVCCIN_CPU0_PWM4
  35  EN  IN  = PVCCIN_CPU0_VDD4
  36  TOUT_FLT  OUT  = PVCCIN_CPU0_ATSEN
  37  LSET  OUT  = PVCCIN_CPU0_LSET4
  38  IOUT  OUT  = PVCCIN_CPU0_IMON4
  39  REFIN  IN  = PVCCIN_CPU0_VREF
  40  PGND3  POWER  = GND
  41  GL2  OUT  = NC

PU11_P0_3  ISL99390FRZTR5935  ISL99390FRZ-TR5935 IC  pkg QFN21_6X5XB  page 268
  1  VOS  IN  = PVCCIN_CPU0_VOS3
  2  AGND  POWER  = GND
  3  VCC  POWER  = PVCCIN_CPU0_VDD3
  4  PVCC  POWER  = PVCCIN_CPU0_PVCC
  5  PGND1  POWER  = GND
  6  GL1  OUT  = NC
  7_9-20_24  PGND2  POWER  = GND
  10_19  SW  OUT  = SW_PVCCIN_CPU0_SW3
  25_29  VIN1  IN  = SW_P12V_PVCCIN_CPU0_FLT
  30  VIN2  IN  = SW_P12V_PVCCIN_CPU0_FLT
  31  DNC  TRI  = NC
  32  PHASE  POWER  = SW_PVCCIN_CPU0_BOOTR3
  33  BOOT  POWER  = SW_PVCCIN_CPU0_BOOT3
  34  PWM  IN  = PVCCIN_CPU0_PWM3
  35  EN  IN  = PVCCIN_CPU0_VDD3
  36  TOUT_FLT  OUT  = PVCCIN_CPU0_ATSEN
  37  LSET  OUT  = PVCCIN_CPU0_LSET3
  38  IOUT  OUT  = PVCCIN_CPU0_IMON3
  39  REFIN  IN  = PVCCIN_CPU0_VREF
  40  PGND3  POWER  = GND
  41  GL2  OUT  = NC

PU12_P0_2  ISL99390FRZTR5935  ISL99390FRZ-TR5935 IC  pkg QFN21_6X5XB  page 267
  1  VOS  IN  = PVCCIN_CPU0_VOS2
  2  AGND  POWER  = GND
  3  VCC  POWER  = PVCCIN_CPU0_VDD2
  4  PVCC  POWER  = PVCCIN_CPU0_PVCC
  5  PGND1  POWER  = GND
  6  GL1  OUT  = NC
  7_9-20_24  PGND2  POWER  = GND
  10_19  SW  OUT  = SW_PVCCIN_CPU0_SW2
  25_29  VIN1  IN  = SW_P12V_PVCCIN_CPU0_FLT
  30  VIN2  IN  = SW_P12V_PVCCIN_CPU0_FLT
  31  DNC  TRI  = NC
  32  PHASE  POWER  = SW_PVCCIN_CPU0_BOOTR2
  33  BOOT  POWER  = SW_PVCCIN_CPU0_BOOT2
  34  PWM  IN  = PVCCIN_CPU0_PWM2
  35  EN  IN  = PVCCIN_CPU0_VDD2
  36  TOUT_FLT  OUT  = PVCCIN_CPU0_ATSEN
  37  LSET  OUT  = PVCCIN_CPU0_LSET2
  38  IOUT  OUT  = PVCCIN_CPU0_IMON2
  39  REFIN  IN  = PVCCIN_CPU0_VREF
  40  PGND3  POWER  = GND
  41  GL2  OUT  = NC

PU13_P0_1  ISL99390FRZTR5935  ISL99390FRZ-TR5935 IC  pkg QFN21_6X5XB  page 267
  1  VOS  IN  = PVCCIN_CPU0_VOS1
  2  AGND  POWER  = GND
  3  VCC  POWER  = PVCCIN_CPU0_VDD1
  4  PVCC  POWER  = PVCCIN_CPU0_PVCC
  5  PGND1  POWER  = GND
  6  GL1  OUT  = NC
  7_9-20_24  PGND2  POWER  = GND
  10_19  SW  OUT  = SW_PVCCIN_CPU0_SW1
  25_29  VIN1  IN  = SW_P12V_PVCCIN_CPU0_FLT
  30  VIN2  IN  = SW_P12V_PVCCIN_CPU0_FLT
  31  DNC  TRI  = NC
  32  PHASE  POWER  = SW_PVCCIN_CPU0_BOOTR1
  33  BOOT  POWER  = SW_PVCCIN_CPU0_BOOT1
  34  PWM  IN  = PVCCIN_CPU0_PWM1
  35  EN  IN  = PVCCIN_CPU0_VDD1
  36  TOUT_FLT  OUT  = PVCCIN_CPU0_ATSEN
  37  LSET  OUT  = PVCCIN_CPU0_LSET1
  38  IOUT  OUT  = PVCCIN_CPU0_IMON1
  39  REFIN  IN  = PVCCIN_CPU0_VREF
  40  PGND3  POWER  = GND
  41  GL2  OUT  = NC

PU14  RAA229126GNPHA0  RAA229126GNP#HA0 IC  pkg QFN48_THXT  page 266
  1  PWM0  OUT  = PVCCFA_EHV_FIVRA_CPU0_PWM1
  2  PWM1  OUT  = PVCCFA_EHV_FIVRA_CPU0_PWM2
  3  PWM2  OUT  = PVCCFA_EHV_FIVRA_CPU0_PWM3
  4  PWM3  OUT  = PVCCFA_EHV_FIVRA_CPU0_PWM4
  5  PWM4  OUT  = PVCCIN_CPU0_PWM8
  6  PWM5  OUT  = PVCCIN_CPU0_PWM7
  7  PWM6  OUT  = PVCCIN_CPU0_PWM6
  8  PWM7  OUT  = PVCCIN_CPU0_PWM5
  9  PWM8  OUT  = PVCCIN_CPU0_PWM4
  10  PWM9  OUT  = PVCCIN_CPU0_PWM3
  11  PWM10  OUT  = PVCCIN_CPU0_PWM2
  12  PWM11  OUT  = PVCCIN_CPU0_PWM1
  13  PMSDA  BI  = SMB_DIO_PVCCIN_CPU0
  14  PMSCL  IN  = SMB_CLK_PVCCIN_CPU0
  15  NPMALERT  OUT  = NC_PVCCIN_CPU0_SMB_ALERT
  16  PG0  OUT  = PWRGD_PVCCIN_CPU0_R
  17  EN0  IN  = PVCCIN_CPU0_EN_R
  18  NVRHOT  OUT  = IRQ_PVCCIN_CPU0_VRHOT_N
  19  \npinalert||npsys_crit\  OUT  = PVCCIN_CPU0_PIN_ALERT
  20  PG1  OUT  = PWRGD_PVCCFA_EHV_FIVRA_CPU0_R
  21  SVCLK  IN  = SVID_CLK_PVCCIN_CPU0_R
  22  SVDATA  BI  = SVID_DIO_PVCCIN_CPU0_R
  23  NSVALERT  OUT  = SVID_ALERT_PVCCIN_CPU0_R
  24  EN1  IN  = PVCCFA_EHV_FIVRA_CPU0_EN_R
  25  VSEN0  IN  = SH_PVCCIN_CPU0_R
  26  RGND0  IN  = VSENSE_PVCCIN_CPU0_DN
  27  CS11  IN  = PVCCIN_CPU0_IMON1
  28  CS10  IN  = PVCCIN_CPU0_IMON2
  29  CS9  IN  = PVCCIN_CPU0_IMON3
  30  CS8  IN  = PVCCIN_CPU0_IMON4
  31  CS7  IN  = PVCCIN_CPU0_IMON5
  32  CS6  IN  = PVCCIN_CPU0_IMON6
  33  CS5  IN  = PVCCIN_CPU0_IMON7
  34  CS4  IN  = PVCCIN_CPU0_IMON8
  35  CS3  IN  = PVCCFA_EHV_FIVRA_CPU0_IMON4
  36  CS2  IN  = PVCCFA_EHV_FIVRA_CPU0_IMON3
  37  CS1  IN  = PVCCFA_EHV_FIVRA_CPU0_IMON2
  38  CS0  IN  = PVCCFA_EHV_FIVRA_CPU0_IMON1
  39  RGND1  IN  = VSENSE_PVCCFA_EHV_FIVRA_CPU0_DN
  40  VSEN1  IN  = SH_PVCCFA_EHV_FIVRA_CPU0_R
  41  CFP  OUT  = PVCCIN_CPU0_VR_FAULT
  42  ADDR_CFG  IN  = PVCCIN_CPU0_ADDR
  43  TEMP0  IN  = PVCCIN_CPU0_ATSEN
  44  \temp1||isys\  IN  = PVCCFA_EHV_FIVRA_CPU0_BTSEN
  45  \vmon||iinsen||vsys||isys\  IN  = PVCCIN_CPU0_CSPIN
  46  \vinsen||vsys\  IN  = PVCCIN_CPU0_VIN_CSNIN
  47  VCC  POWER  = PVCCIN_CPU0_VCC
  48  VCCS  POWER  = PVCCIN_CPU0_VREF
  TH  TH_GND  POWER  = GND

PU17  ISL99390FRZTR5935  ISL99390FRZ-TR5935 IC  pkg QFN21_6X5XB  page 297
  1  VOS  IN  = PVCCD_HV_CPU1_VOS
  2  AGND  POWER  = GND
  3  VCC  POWER  = PVCCD_HV_CPU1_VDD1
  4  PVCC  POWER  = PVCCFA_EHV_CPU1_PVCC
  5  PGND1  POWER  = GND
  6  GL1  OUT  = NC
  7_9-20_24  PGND2  POWER  = GND
  10_19  SW  OUT  = SW_PVCCD_HV_CPU1_SW1
  25_29  VIN1  IN  = SW_P12V_PVCCINFAON_CPU1_FLT
  30  VIN2  IN  = SW_P12V_PVCCINFAON_CPU1_FLT
  31  DNC  TRI  = NC
  32  PHASE  POWER  = SW_PVCCD_HV_CPU1_BOOTR1
  33  BOOT  POWER  = SW_PVCCD_HV_CPU1_BOOT1
  34  PWM  IN  = PVCCD_HV_CPU1_APWM1
  35  EN  IN  = PVCCD_HV_CPU1_VDD1
  36  TOUT_FLT  OUT  = PVCCD_HV_CPU1_ATSEN
  37  LSET  OUT  = PVCCD_HV_CPU1_LSET1
  38  IOUT  OUT  = PVCCD_HV_CPU1_ACSP1
  39  REFIN  IN  = PVCCD_HV_CPU1_VREF
  40  PGND3  POWER  = GND
  41  GL2  OUT  = NC

PU18  ISL69260IRAZT  ISL69260IRAZ-T IC  pkg QFN40_TH_0-4_5X5XE  page 296
  1  PWM0  OUT  = NC_PVCCD_HV_CPU1_APWM8
  2  PWM1  OUT  = NC_PVCCD_HV_CPU1_APWM7
  3  PWM2  OUT  = NC_PVCCD_HV_CPU1_APWM6
  4  PWM3  OUT  = NC_PVCCD_HV_CPU1_APWM5
  5  PWM4  OUT  = NC_PVCCD_HV_CPU1_APWM4
  6  PWM5  OUT  = NC_PVCCD_HV_CPU1_APWM3
  7  PWM6  OUT  = NC_PVCCD_HV_CPU1_APWM2
  8  PWM7  OUT  = PVCCD_HV_CPU1_APWM1
  9  PMSDA  BI  = SMB_DIO_PVCCD_HV_CPU1
  10  PMSCL  IN  = SMB_CLK_PVCCD_HV_CPU1
  11  \npmalert#\  OUT  = NC_PVCCD_HV_CPU1_SMB_ALERT
  12  PG0  OUT  = PWRGD_PVCCD_HV_CPU1_R
  13  EN0  IN  = PVCCD_HV_CPU1_EN_R
  14  \nvrhot#\  OUT  = IRQ_PVCCD_CPU1_VRHOT_LVC3_R_N
  15  \npinalert#||npsyscrit#\  OUT  = PVCCD_HV_CPU1_PIN_ALT
  16  PG1  OUT  = NC_PVCCD_HV_CPU1_BVR_RDY
  17  SVCLK  IN  = SVID_CLK_PVCCD_HV_CPU1_R
  18  SVDATA  BI  = SVID_DIO_PVCCD_HV_CPU1_R
  19  \nsvalert#\  OUT  = SVID_ALERT_PVCCD_HV_CPU1_R
  20  EN1  IN  = GND
  21  VSEN0  IN  = SH_PVCCD_HV_CPU1_R
  22  RGND0  IN  = VSENSE_PVCCD_HV_CPU1_DN
  23  CS7  IN  = PVCCD_HV_CPU1_ACSP1
  24  CS6  IN  = NC_PVCCD_HV_CPU1_ACSP2
  25  CS5  IN  = NC_PVCCD_HV_CPU1_ACSP3
  26  CS4  IN  = NC_PVCCD_HV_CPU1_ACSP4
  27  CS3  IN  = NC_PVCCD_HV_CPU1_ACSP5
  28  CS2  IN  = NC_PVCCD_HV_CPU1_ACSP6
  29  CS1  IN  = NC_PVCCD_HV_CPU1_ACSP7
  30  CS0  IN  = NC_PVCCD_HV_CPU1_ACSP8
  31  RGND1  IN  = GND
  32  VSEN1  IN  = GND
  33  CFP  OUT  = PVCCD_HV_CPU1_FAULT
  34  ADDR_CFG  IN  = PVCCD_HV_CPU1_ADDR
  35  TEMP0  IN  = PVCCD_HV_CPU1_ATSEN
  36  \temp1||isys\  IN  = PVCCD_HV_CPU1_ISYS_R
  37  \vmon||iinsen||vsys||isys\  IN  = PVCCD_HV_CPU1_ISENSE_P
  38  \vinsen||vsys\  IN  = PVCCD_HV_CPU1_ISENSE_N
  39  VCC  POWER  = PVCCD_HV_CPU1_VCC
  40  VCCS  POWER  = PVCCD_HV_CPU1_VREF
  TH  TH_GND  POWER  = GND

PU22  ISL69260IRAZT  ISL69260IRAZ-T IC  pkg QFN40_TH_0-4_5X5XE  page 292
  1  PWM0  OUT  = PVCCFA_EHV_CPU1_BPWM1
  2  PWM1  OUT  = NC_PVCCINFAON_CPU1_APWM7
  3  PWM2  OUT  = NC_PVCCINFAON_CPU1_APWM6
  4  PWM3  OUT  = NC_PVCCINFAON_CPU1_APWM5
  5  PWM4  OUT  = NC_PVCCINFAON_CPU1_APWM4
  6  PWM5  OUT  = NC_PVCCINFAON_CPU1_APWM3
  7  PWM6  OUT  = PVCCINFAON_CPU1_APWM2
  8  PWM7  OUT  = PVCCINFAON_CPU1_APWM1
  9  PMSDA  BI  = SMB_DIO_PVCCINFAON_CPU1
  10  PMSCL  IN  = SMB_CLK_PVCCINFAON_CPU1
  11  \npmalert#\  OUT  = NC_PVCCINFAON_CPU1_SMB_ALERT
  12  PG0  OUT  = PWRGD_PVCCINFAON_CPU1_R
  13  EN0  IN  = PVCCINFAON_CPU1_EN_R
  14  \nvrhot#\  OUT  = IRQ_PVCCFA_CPU1_VRHOT_N
  15  \npinalert#||npsyscrit#\  OUT  = PVCCINFAON_CPU1_PIN_ALERT
  16  PG1  OUT  = PWRGD_PVCCFA_EHV_CPU1_R
  17  SVCLK  IN  = SVID_CLK_PVCCINFAON_CPU1_R
  18  SVDATA  BI  = SVID_DIO_PVCCINFAON_CPU1_R
  19  \nsvalert#\  OUT  = SVID_ALERT_PVCCINFAON_CPU1_R
  20  EN1  IN  = PVCCFA_EHV_CPU1_EN_R
  21  VSEN0  IN  = SH_PVCCINFAON_CPU1_R
  22  RGND0  IN  = VSENSE_PVCCINFAON_CPU1_DN
  23  CS7  IN  = PVCCINFAON_CPU1_ACSP1
  24  CS6  IN  = PVCCINFAON_CPU1_ACSP2
  25  CS5  IN  = NC_PVCCINFAON_CPU1_ACSP3
  26  CS4  IN  = NC_PVCCINFAON_CPU1_ACSP4
  27  CS3  IN  = NC_PVCCINFAON_CPU1_ACSP5
  28  CS2  IN  = NC_PVCCINFAON_CPU1_ACSP6
  29  CS1  IN  = NC_PVCCINFAON_CPU1_ACSP7
  30  CS0  IN  = PVCCFA_EHV_CPU1_BCSP1
  31  RGND1  IN  = VSENSE_PVCCFA_EHV_CPU1_DN
  32  VSEN1  IN  = SH_PVCCFA_EHV_CPU1_R
  33  CFP  OUT  = PVCCINFAON_CPU1_VR_FAULT
  34  ADDR_CFG  IN  = PVCCINFAON_CPU1_ADDR
  35  TEMP0  IN  = PVCCINFAON_CPU1_ATSEN
  36  \temp1||isys\  IN  = PVCCFA_EHV_CPU1_BTSEN
  37  \vmon||iinsen||vsys||isys\  IN  = PVCCINFAON_CPU1_CSPIN
  38  \vinsen||vsys\  IN  = PVCCINFAON_CPU1_VIN_CSNIN
  39  VCC  POWER  = PVCCINFAON_CPU1_VCC
  40  VCCS  POWER  = PVCCINFAON_CPU1_VREF
  TH  TH_GND  POWER  = GND

PU23_P1_8  ISL99390FRZTR5935  ISL99390FRZ-TR5935 IC  pkg QFN21_6X5XB  page 288
  1  VOS  IN  = PVCCIN_CPU1_VOS8
  2  AGND  POWER  = GND
  3  VCC  POWER  = PVCCIN_CPU1_VDD8
  4  PVCC  POWER  = PVCCIN_CPU1_PVCC
  5  PGND1  POWER  = GND
  6  GL1  OUT  = NC
  7_9-20_24  PGND2  POWER  = GND
  10_19  SW  OUT  = SW_PVCCIN_CPU1_SW8
  25_29  VIN1  IN  = SW_P12V_PVCCIN_CPU1_FLT
  30  VIN2  IN  = SW_P12V_PVCCIN_CPU1_FLT
  31  DNC  TRI  = NC
  32  PHASE  POWER  = SW_PVCCIN_CPU1_BOOTR8
  33  BOOT  POWER  = SW_PVCCIN_CPU1_BOOT8
  34  PWM  IN  = PVCCIN_CPU1_PWM8
  35  EN  IN  = PVCCIN_CPU1_VDD8
  36  TOUT_FLT  OUT  = PVCCIN_CPU1_ATSEN
  37  LSET  OUT  = PVCCIN_CPU1_LSET8
  38  IOUT  OUT  = PVCCIN_CPU1_IMON8
  39  REFIN  IN  = PVCCIN_CPU1_VREF
  40  PGND3  POWER  = GND
  41  GL2  OUT  = NC
